FILE_TYPE = CONNECTIVITY;
{Allegro Design Entry HDL 17.2-2016 S081 (4005846) 1/11/2022}
"PAGE_NUMBER" = 175;
0"NC";
1"P3V3_AUX\g";
2"GND\g";
3"GND\g";
4"GND\g";
5"GND\g";
6"GND\g";
7"SMB_SML1_PMBUS_3V3AUX_PCH_SCL_R1";
8"JTAG_TRC_PCH_PTI<11>"CDS_PHYS_NET_NAME"FM_PCH_SLP_S4_N";
9"JTAG_TRC_PCH_PTI<13>"CDS_PHYS_NET_NAME"FM_PCH_SLP_S4_N";
10"JTAG_TRC_PCH_PTI<14>"CDS_PHYS_NET_NAME"FM_PCH_SLP_S4_N";
11"JTAG_TRC_PCH_PTI<15>"CDS_PHYS_NET_NAME"FM_PCH_SLP_S4_N";
12"JTAG_TRC_PCH_PTI1_CLK"CDS_PHYS_NET_NAME"FM_PCH_SLP_S4_N";
13"IRQ_LPC_PIRQA_N_ESPI_ALERT0_N"CDS_PHYS_NET_NAME"FM_PCH_SLP_S4_N";
14"ESPI_LAD0_DATA_IO3"CDS_PHYS_NET_NAME"FM_PCH_SLP_S4_N";
15"IRQ_LPC_SERIRQ_ESPI_CS1_N"CDS_PHYS_NET_NAME"FM_PCH_SLP_S4_N";
16"PD_PCH_GPPC_A_14"CDS_PHYS_NET_NAME"FM_PCH_SLP_S4_N";
17"PD_PCH_GPPC_A_15"CDS_PHYS_NET_NAME"FM_PCH_SLP_S4_N";
18"FM_PCH_SATA_RAID_KEY"CDS_PHYS_NET_NAME"FM_PCH_SLP_S4_N";
19"FM_BMC_READY_R_N"CDS_PHYS_NET_NAME"TP_PCH_GPPC_A_14";
20"E1S_0_CLKREQ_N";
21"CLK_24M_66M_LPC0_ESPI"CDS_PHYS_NET_NAME"FM_PCH_SLP_S4_N";
22"ESPI_LAD0_DATA_IO2"CDS_PHYS_NET_NAME"FM_PCH_SLP_S4_N";
23"ESPI_LFRAME_N_BMC_CS0_N"CDS_PHYS_NET_NAME"FM_PCH_SLP_S4_N";
24"ESPI_LAD0_DATA_IO1"CDS_PHYS_NET_NAME"FM_PCH_SLP_S4_N";
25"ESPI_ALERT1_N_LPC_RCIN_N"CDS_PHYS_NET_NAME"FM_PCH_SLP_S4_N";
26"JTAG_TRC_PCH_PTI<12>"CDS_PHYS_NET_NAME"FM_PCH_SLP_S4_N";
27"JTAG_TRC_PCH_PTI<8>"CDS_PHYS_NET_NAME"FM_PCH_SLP_S4_N";
28"JTAG_TRC_PCH_PTI<7>"CDS_PHYS_NET_NAME"FM_PCH_SLP_S4_N";
29"JTAG_TRC_PCH_PTI<9>"CDS_PHYS_NET_NAME"FM_PCH_SLP_S4_N";
30"JTAG_TRC_PCH_PTI<5>"CDS_PHYS_NET_NAME"FM_PCH_SLP_S4_N";
31"PU_OC5_USB_N";
32"PU_OC3_USB_N";
33"JTAG_TRC_PCH_PTI<3>"CDS_PHYS_NET_NAME"FM_PCH_SLP_S4_N";
34"JTAG_TRC_PCH_PTI<1>"CDS_PHYS_NET_NAME"FM_PCH_SLP_S4_N";
35"PU_OC2_USB_N";
36"PU_SMB_SML3_3V3AUX_PCH_SDA";
37"PU_SMB_SML3_3V3AUX_PCH_SCL";
38"USB_OC1_REAR_R_N";
39"IRQ_SML0_ALERT_N";
40"PU_OC3_USB_N";
41"PU_OC4_USB_N";
42"PU_OC5_USB_N";
43"PU_OC6_USB_N";
44"E1S_0_CLK_OE_N";
45"PD_PCH_GPPC_A_15"CDS_PHYS_NET_NAME"FM_PCH_SLP_S4_N";
46"PD_PCH_GPPC_A_18"CDS_PHYS_NET_NAME"FM_PCH_SLP_S4_N";
47"PD_PCH_GPPC_A_19"CDS_PHYS_NET_NAME"FM_PCH_SLP_S4_N";
48"PU_SMB_SML4_3V3AUX_PCH_SDA";
49"PU_PCH_PLD_3V3AUX_ALERT_N";
50"PU_SMB_PCH_PLD_3V3AUX_SDA";
51"PU_SMB_PCH_PLD_3V3AUX_SCL";
52"PU_SMB_SML4_3V3AUX_PCH_SCL";
53"SMB_SML0B_3V3AUX_SDA";
54"FM_PMBUS_ALERT_B_EN";
55"SMB_SML0B_3V3AUX_SCL";
56"FM_PCHHOT_R_N"CDS_PHYS_NET_NAME"CLK_100M_DB2000_CPU0_BCLK0_DP";
57"USB_OC1_REAR_N"CDS_PHYS_NET_NAME"CLK_100M_DB2000_CPU0_BCLK0_DP";
58"FM_PCH_CRASHLOG_TRIG_N"CDS_PHYS_NET_NAME"CLK_100M_DB2000_CPU0_BCLK0_DP";
59"IRQ_SML1_PMBUS_BMC_ALERT_N"CDS_PHYS_NET_NAME"IRQ_SML0_ALERT_R_N";
60"SMB_SML1_PMBUS_3V3AUX_PCH_SCL";
61"FM_BIOS_DEBUG_EN_N"CDS_PHYS_NET_NAME"CLK_100M_DB2000_CPU0_BCLK0_DP";
62"JTAG_TRC_PCH_PTI<2>"CDS_PHYS_NET_NAME"FM_PCH_SLP_S4_N";
63"PU_OC2_USB_N";
64"PU_OC4_USB_N";
65"E1S_0_CLK_OE_N";
66"JTAG_TRC_PCH_PTI<4>"CDS_PHYS_NET_NAME"FM_PCH_SLP_S4_N";
67"PU_OC6_USB_N";
68"JTAG_TRC_PCH_PTI<6>"CDS_PHYS_NET_NAME"FM_PCH_SLP_S4_N";
69"JTAG_TRC_PCH_PTI<10>"CDS_PHYS_NET_NAME"FM_PCH_SLP_S4_N";
70"ESPI_LAD0_DATA_IO0"CDS_PHYS_NET_NAME"FM_PCH_SLP_S4_N";
71"E1S_0_PRSNT_N";
72"SMB_SML0_3V3AUX_PCH_SDA";
73"SMB_SML1_PMBUS_3V3AUX_PCH_SDA_R1";
74"RST_ESPI_RESET_N"CDS_PHYS_NET_NAME"FM_PCH_SLP_S4_N";
75"PD_PCH_GPPC_A_10"CDS_PHYS_NET_NAME"FM_PCH_SLP_S4_N";
76"M2_SSD0_CLKREQ_EN_N"CDS_PHYS_NET_NAME"FM_PCH_SLP_S4_N";
77"E1S_0_PERST1_CLKREQ_N"CDS_PHYS_NET_NAME"E1S_0_PERST1_CLKREQ_N";
78"PU_PCH_PLD_3V3AUX_ALERT_N";
79"PU_SMB_PCH_PLD_3V3AUX_SDA";
80"PU_SMB_PCH_PLD_3V3AUX_SCL";
81"FM_ADR_MODE1";
82"FM_BIOS_POST_CMPLT_N";
83"FM_THROTTLE_N";
84"PU_SMB_SML3_3V3AUX_PCH_SCL";
85"PU_SMB_SML3_3V3AUX_PCH_SDA";
86"PU_SMB_SML4_3V3AUX_PCH_SCL";
87"PU_SMB_SML4_3V3AUX_PCH_SDA";
88"PD_PCH_GPPC_C10";
89"PD_PCH_GPPC_C9";
90"SMB_SML1_PMBUS_3V3AUX_PCH_SDA_R1";
91"IRQ_SML1_PMBUS_ALERT_N";
92"FM_PMBUS_ALERT_B_EN";
93"PD_PCH_GPPC_C5";
94"SMB_SML1_PMBUS_3V3AUX_PCH_SCL_R1";
95"IRQ_SML0_ALERT_N";
96"SMB_SML0B_3V3AUX_SDA";
97"SMB_SML0B_3V3AUX_SCL";
98"FM_BIOS_DEBUG_EN_R_N";
99"SMB_SML0_3V3AUX_PCH_SCL";
100"SMB_SML0_3V3AUX_PCH_SDA";
101"FM_PCH_BOOT_BIOS_STRAP";
102"FM_PCH_GLB_RST_WARN_N";
103"FM_PLT_BMC_THERMTRIP_R_N";
104"FM_CPU_RMCA_CATERR_DLY_N";
105"FM_BIOS_IMAGE_SWAP_N";
106"FM_PCHHOT_N";
107"FM_ADR_COMPLETE";
108"FM_ADR_TRIGGER_R_N";
109"PU_PCH_VRALERT_N";
110"FM_ADR_ACK";
111"IRQ_PCH_SCI_WHEA_N";
112"PU_LPC_PME_N";
113"FM_PCH_CRASHLOG_TRIG_N";
114"FM_ESPI_FLASH_MODE";
115"RST_PLTRST_N";
116"SMB_HOST_BMC_3V3AUX_SCL";
117"FM_FLASH_SECURITY_STRAP";
118"SMB_HOST_BMC_3V3AUX_SDA";
119"PD_PCH_GPPC_A_19"CDS_PHYS_NET_NAME"FM_PCH_SLP_S4_N";
120"PD_PCH_GPPC_A_18"CDS_PHYS_NET_NAME"FM_PCH_SLP_S4_N";
121"IRQ_BMC_PCH_NMI"CDS_PHYS_NET_NAME"FM_PCH_SLP_S4_N";
122"JTAG_TRC_PCH_PTI<0>"CDS_PHYS_NET_NAME"FM_PCH_SLP_S4_N";
123"JTAG_TRC_PCH_PTI0_CLK"CDS_PHYS_NET_NAME"FM_PCH_SLP_S4_N";
124"USB_OC1_REAR_R_N";
125"TP_PCH_GPP_D_2";
126"TP_PCH_GPP_D_20";
127"PD_PCH_GPPC_A_14"CDS_PHYS_NET_NAME"FM_PCH_SLP_S4_N";
128"PD_PCH_GPPC_A_10"CDS_PHYS_NET_NAME"FM_PCH_SLP_S4_N";
129"PD_PCH_GPPC_C10";
130"PD_PCH_GPPC_C5";
131"SMB_SML1_PMBUS_3V3AUX_PCH_SDA";
132"IRQ_SML0_ALERT_N"CDS_PHYS_NET_NAME"CLK_100M_DB2000_CPU0_BCLK0_DP";
133"IRQ_SML1_PMBUS_PLD_ALERT_N"CDS_PHYS_NET_NAME"IRQ_SML0_ALERT_R_N";
134"IRQ_SML0_ALERT_R_N"CDS_PHYS_NET_NAME"CLK_100M_DB2000_CPU0_BCLK0_DP";
135"FM_PCH_SATA_RAID_KEY"CDS_PHYS_NET_NAME"FM_PCH_SATA_RAID_KEY";
136"FM_PCHHOT_N"CDS_PHYS_NET_NAME"CLK_100M_DB2000_CPU0_BCLK0_DP";
137"USB_OC1_REAR_R_N"CDS_PHYS_NET_NAME"CLK_100M_DB2000_CPU0_BCLK0_DP";
138"FM_PCH_CRASHLOG_TRIG_R_N"CDS_PHYS_NET_NAME"CLK_100M_DB2000_CPU0_BCLK0_DP";
139"IRQ_SML1_PMBUS_ALERT_N"CDS_PHYS_NET_NAME"IRQ_SML0_ALERT_N";
140"PD_PCH_GPPC_C9";
141"IRQ_BMC_PCH_NMI"CDS_PHYS_NET_NAME"IRQ_BMC_PCH_NMI";
142"SMB_SML1_PMBUS_3V3AUX_PCH_SCL_R1";
143"SMB_SML1_PMBUS_3V3AUX_PCH_SDA_R1";
144"FM_BIOS_DEBUG_EN_R_N"CDS_PHYS_NET_NAME"CLK_100M_DB2000_CPU0_BCLK0_DP";
145"IRQ_BMC_PCH_NMI_R"CDS_PHYS_NET_NAME"FM_PCH_SLP_S4_N";
146"SMB_SML0_3V3AUX_PCH_SCL";
%"Q_RES"
"1","(2950,900)","0","pure_quanta","I102";
;
PART_NUMBER"CS03322FB03"
VALUE"33.2"
TOLERANCE"1%"
MATERIAL"CHIP"
$LOCATION"R699"
CDS_LIB"pure_quanta"
WATTAGE"1/16W"
PACK_TYPE"0402LF"
CDS_LOCATION"R699"
$SEC"1"
CDS_SEC"1";
"B"
$PN"2"58;
"A"
$PN"1"138;
%"Q_RES"
"1","(3475,-775)","0","pure_quanta","I109";
;
PART_NUMBER"CS22002FB07"
VALUE"2K"
TOLERANCE"1%"
MATERIAL"CHIP"
$LOCATION"R1451"
WATTAGE"1/16W"
PACK_TYPE"0402LF"
CDS_LIB"pure_quanta"
CDS_LOCATION"R1451"
$SEC"1"
CDS_SEC"1";
"B"
$PN"2"1;
"A"
$PN"1"37;
%"UNIVERSAL_POWER"
"1","(4525,100)","0","logical_power","I111";
;
HDL_POWER"P3V3_AUX"
CDS_LIB"logical_power";
"A"1;
%"Q_RES"
"1","(3475,-825)","0","pure_quanta","I112";
;
PART_NUMBER"CS22002FB07"
TOLERANCE"1%"
MATERIAL"CHIP"
VALUE"2K"
$LOCATION"R1452"
PACK_TYPE"0402LF"
WATTAGE"1/16W"
CDS_LIB"pure_quanta"
CDS_LOCATION"R1452"
$SEC"1"
CDS_SEC"1";
"B"
$PN"2"1;
"A"
$PN"1"36;
%"Q_RES"
"1","(3475,-925)","0","pure_quanta","I120";
;
PART_NUMBER"CS22002FB07"
MATERIAL"CHIP"
TOLERANCE"1%"
VALUE"2K"
$LOCATION"R1453"
CDS_LIB"pure_quanta"
WATTAGE"1/16W"
PACK_TYPE"0402LF"
CDS_LOCATION"R1453"
$SEC"1"
CDS_SEC"1";
"B"
$PN"2"1;
"A"
$PN"1"52;
%"Q_RES"
"1","(3475,-975)","0","pure_quanta","I121";
;
PART_NUMBER"CS22002FB07"
TOLERANCE"1%"
MATERIAL"CHIP"
VALUE"2K"
$LOCATION"R1454"
CDS_LIB"pure_quanta"
PACK_TYPE"0402LF"
WATTAGE"1/16W"
CDS_LOCATION"R1454"
$SEC"1"
CDS_SEC"1";
"B"
$PN"2"1;
"A"
$PN"1"48;
%"Q_RES"
"1","(2950,300)","0","pure_quanta","I125";
;
PART_NUMBER"CS11002FB07"
VALUE"100"
PACK_TYPE"0402LF"
WATTAGE"1/16W"
MATERIAL"CHIP"
TOLERANCE"1%"
$LOCATION"R1487"
CDS_LIB"pure_quanta"
CDS_LOCATION"R1487"
$SEC"1"
CDS_SEC"1";
"B"
$PN"2"4;
"A"
$PN"1"135;
%"UNIVERSAL_GND"
"1","(3450,175)","0","logical_power","I126";
;
CDS_LIB"logical_power"
HDL_POWER"GND";
"A"4;
%"Q_RES"
"1","(3475,-625)","0","pure_quanta","I137";
;
PART_NUMBER"CS22002FB07"
TOLERANCE"1%"
WATTAGE"1/16W"
PACK_TYPE"0402LF"
VALUE"2K"
MATERIAL"CHIP"
$LOCATION"R1545"
CDS_LIB"pure_quanta"
CDS_LOCATION"R1545"
$SEC"1"
CDS_SEC"1";
"B"
$PN"2"1;
"A"
$PN"1"55;
%"Q_RES"
"1","(3475,-675)","0","pure_quanta","I138";
;
PART_NUMBER"CS22002FB07"
TOLERANCE"1%"
VALUE"2K"
MATERIAL"CHIP"
$LOCATION"R1546"
CDS_LIB"pure_quanta"
WATTAGE"1/16W"
PACK_TYPE"0402LF"
CDS_LOCATION"R1546"
$SEC"1"
CDS_SEC"1";
"B"
$PN"2"1;
"A"
$PN"1"53;
%"Q_RES"
"1","(3475,-1125)","0","pure_quanta","I141";
;
PART_NUMBER"CS22002FB07"
TOLERANCE"1%"
MATERIAL"CHIP"
VALUE"2K"
$LOCATION"R1582"
WATTAGE"1/16W"
PACK_TYPE"0402LF"
CDS_LIB"pure_quanta"
CDS_LOCATION"R1582"
$SEC"1"
CDS_SEC"1";
"B"
$PN"2"1;
"A"
$PN"1"50;
%"Q_RES"
"1","(3475,-1075)","0","pure_quanta","I142";
;
PART_NUMBER"CS22002FB07"
MATERIAL"CHIP"
VALUE"2K"
TOLERANCE"1%"
$LOCATION"R1581"
WATTAGE"1/16W"
PACK_TYPE"0402LF"
CDS_LIB"pure_quanta"
CDS_LOCATION"R1581"
$SEC"1"
CDS_SEC"1";
"B"
$PN"2"1;
"A"
$PN"1"51;
%"Q_RES"
"1","(3475,-1175)","0","pure_quanta","I144";
;
PART_NUMBER"CS31002FB08"
TOLERANCE"1%"
WATTAGE"1/16W"
PACK_TYPE"0402LF"
MATERIAL"CHIP"
VALUE"10K"
$LOCATION"R1583"
CDS_LIB"pure_quanta"
CDS_LOCATION"R1583"
$SEC"1"
CDS_SEC"1";
"B"
$PN"2"1;
"A"
$PN"1"49;
%"Q_RES"
"1","(2950,1275)","0","pure_quanta","I148";
;
PART_NUMBER"CS03322FB03"
MATERIAL"CHIP"
TOLERANCE"1%"
WATTAGE"1/16W"
VALUE"33.2"
PACK_TYPE"0402LF"
$LOCATION"R1600"
CDS_LIB"pure_quanta"
CDS_LOCATION"R1600"
$SEC"1"
CDS_SEC"1";
"B"
$PN"2"134;
"A"
$PN"1"132;
%"Q_RES"
"1","(3475,-25)","0","pure_quanta","I151";
;
PART_NUMBER"CS31002FB08"
WATTAGE"1/16W"
PACK_TYPE"0402LF"
VALUE"10K"
TOLERANCE"1%"
MATERIAL"CHIP"
$LOCATION"R1601"
CDS_LIB"pure_quanta"
CDS_LOCATION"R1601"
$SEC"1"
CDS_SEC"1";
"B"
$PN"2"1;
"A"
$PN"1"39;
%"Q_RES"
"1","(2950,1150)","0","pure_quanta","I178";
;
PART_NUMBER"CS03322FB03"
VALUE"33.2"
MATERIAL"CHIP"
TOLERANCE"1%"
$LOCATION"R1656"
WATTAGE"1/16W"
PACK_TYPE"0402LF"
CDS_LIB"pure_quanta"
CDS_LOCATION"R1656"
$SEC"1"
CDS_SEC"1";
"B"
$PN"2"133;
"A"
$PN"1"139;
%"Q_RES"
"1","(2950,1025)","0","pure_quanta","I180";
;
PART_NUMBER"CS03322FB03"
MATERIAL"CHIP"
TOLERANCE"1%"
VALUE"33.2"
$LOCATION"R1657"
WATTAGE"1/16W"
PACK_TYPE"0402LF"
CDS_LIB"pure_quanta"
CDS_LOCATION"R1657"
$SEC"1"
CDS_SEC"1";
"B"
$PN"2"59;
"A"
$PN"1"139;
%"Q_RES"
"1","(3475,-125)","0","pure_quanta","I181";
;
PART_NUMBER"CS31002FB08"
VALUE"10K"
TOLERANCE"1%"
MATERIAL"CHIP"
$LOCATION"R1659"
CDS_LIB"pure_quanta"
WATTAGE"1/16W"
PACK_TYPE"0402LF"
CDS_LOCATION"R1659"
$SEC"1"
CDS_SEC"1";
"B"
$PN"2"1;
"A"
$PN"1"54;
%"Q_RES"
"1","(3475,-175)","0","pure_quanta","I188";
;
PART_NUMBER"CS31002FB08"
TOLERANCE"1%"
MATERIAL"CHIP"
VALUE"10K"
$LOCATION"R1828"
CDS_LIB"pure_quanta"
PACK_TYPE"0402LF"
WATTAGE"1/16W"
CDS_LOCATION"R1828"
$SEC"1"
CDS_SEC"1";
"B"
$PN"2"1;
"A"
$PN"1"38;
%"Q_RES"
"1","(2950,775)","0","pure_quanta","I193";
;
PART_NUMBER"CS03322FB03"
MATERIAL"CHIP"
TOLERANCE"1%"
VALUE"33.2"
$LOCATION"R1827"
WATTAGE"1/16W"
PACK_TYPE"0402LF"
CDS_LIB"pure_quanta"
CDS_LOCATION"R1827"
$SEC"1"
CDS_SEC"1";
"B"
$PN"2"57;
"A"
$PN"1"137;
%"Q_RES"
"1","(2950,650)","0","pure_quanta","I213";
;
PART_NUMBER"CS03322FB03"
TOLERANCE"1%"
VALUE"33.2"
MATERIAL"CHIP"
$LOCATION"R474"
PACK_TYPE"0402LF"
WATTAGE"1/16W"
CDS_LIB"pure_quanta"
CDS_LOCATION"R474"
$SEC"1"
CDS_SEC"1";
"B"
$PN"2"56;
"A"
$PN"1"136;
%"Q_RES"
"1","(-1850,225)","0","pure_quanta","I222";
;
PART_NUMBER"CS03322FB03"
WATTAGE"1/16W"
VALUE"33.2"
MATERIAL"CHIP"
TOLERANCE"1%"
PACK_TYPE"0402LF"
$LOCATION"R1268"
CDS_LIB"pure_quanta"
CDS_LOCATION"R1268"
$SEC"1"
CDS_SEC"1";
"B"
$PN"2"141;
"A"
$PN"1"145;
%"UNIVERSAL_GND"
"1","(-650,-25)","0","logical_power","I224";
;
CDS_LIB"logical_power"
HDL_POWER"GND";
"A"3;
%"Q_RES"
"1","(-1100,75)","0","pure_quanta","I225";
;
PART_NUMBER"CS24752FB03"
VALUE"4.75K"
PACK_TYPE"0402LF"
WATTAGE"1/16W"
TOLERANCE"1%"
MATERIAL"CHIP"
$LOCATION"R1269"
CDS_LIB"pure_quanta"
CDS_LOCATION"R1269"
$SEC"1"
CDS_SEC"1";
"B"
$PN"2"3;
"A"
$PN"1"141;
%"Q_RES"
"1","(3475,-275)","0","pure_quanta","I234";
;
PART_NUMBER"CS31002FB08"
MATERIAL"CHIP"
TOLERANCE"1%"
VALUE"10K"
$LOCATION"R635"
CDS_LIB"pure_quanta"
WATTAGE"1/16W"
PACK_TYPE"0402LF"
CDS_LOCATION"R635"
$SEC"1"
CDS_SEC"1";
"B"
$PN"2"1;
"A"
$PN"1"40;
%"Q_RES"
"1","(3475,-325)","0","pure_quanta","I236";
;
PART_NUMBER"CS31002FB08"
MATERIAL"CHIP"
VALUE"10K"
TOLERANCE"1%"
$LOCATION"R727"
CDS_LIB"pure_quanta"
WATTAGE"1/16W"
PACK_TYPE"0402LF"
CDS_LOCATION"R727"
$SEC"1"
CDS_SEC"1";
"B"
$PN"2"1;
"A"
$PN"1"41;
%"Q_RES"
"1","(3475,-375)","0","pure_quanta","I239";
;
PART_NUMBER"CS31002FB08"
VALUE"10K"
TOLERANCE"1%"
MATERIAL"CHIP"
$LOCATION"R770"
PACK_TYPE"0402LF"
WATTAGE"1/16W"
CDS_LIB"pure_quanta"
CDS_LOCATION"R770"
$SEC"1"
CDS_SEC"1";
"B"
$PN"2"1;
"A"
$PN"1"42;
%"Q_RES"
"1","(3475,-425)","0","pure_quanta","I241";
;
PART_NUMBER"CS31002FB08"
TOLERANCE"1%"
VALUE"10K"
MATERIAL"CHIP"
$LOCATION"R913"
PACK_TYPE"0402LF"
WATTAGE"1/16W"
CDS_LIB"pure_quanta"
CDS_LOCATION"R913"
$SEC"1"
CDS_SEC"1";
"B"
$PN"2"1;
"A"
$PN"1"43;
%"Q_RES"
"1","(2950,1650)","0","pure_quanta","I253";
;
PART_NUMBER"CS00002JB13"
TOLERANCE"5%"
PACK_TYPE"0402LF"
WATTAGE"1/16W"
VALUE"0"
MATERIAL"CHIP"
$LOCATION"R2971"
CDS_LIB"pure_quanta"
CDS_LOCATION"R2971"
$SEC"1"
CDS_SEC"1";
"B"
$PN"2"144;
"A"
$PN"1"61;
%"CONN3_210HP1030BR1"
"1","(-3125,1525)","2","pure_quanta","I256";
;
PART_NUMBER"DFHD03MS213"
VALUE"CONN3_210-HP1-030BR1"
MATERIAL"EMPTY"
PART_TYPE"THLF"
$LOCATION"JP4"
CDS_LMAN_SYM_OUTLINE"-50,100,50,-100"
NEEDS_NO_SIZE"TRUE"
CDS_LIB"pure_quanta"
CDS_LOCATION"JP4"
$SEC"1"
CDS_SEC"1";
"1"
$PN"1"146;
"2"
$PN"2"5;
"3"
$PN"3"72;
%"UNIVERSAL_GND"
"1","(-2825,1350)","0","logical_power","I257";
;
HDL_POWER"GND"
CDS_LIB"logical_power";
"A"5;
%"UNIVERSAL_GND"
"1","(-2825,775)","0","logical_power","I260";
;
HDL_POWER"GND"
CDS_LIB"logical_power";
"A"6;
%"CONN3_210HP1030BR1"
"1","(-3125,950)","2","pure_quanta","I263";
;
PART_NUMBER"DFHD03MS213"
PART_TYPE"THLF"
MATERIAL"EMPTY"
VALUE"CONN3_210-HP1-030BR1"
$LOCATION"JP9"
CDS_LMAN_SYM_OUTLINE"-50,100,50,-100"
NEEDS_NO_SIZE"TRUE"
CDS_LIB"pure_quanta"
CDS_LOCATION"JP9"
$SEC"1"
CDS_SEC"1";
"1"
$PN"1"7;
"2"
$PN"2"6;
"3"
$PN"3"73;
%"Q_RES"
"1","(3475,-225)","0","pure_quanta","I272";
;
PART_NUMBER"CS31002FB08"
MATERIAL"CHIP"
TOLERANCE"1%"
VALUE"10K"
$LOCATION"R3938"
PACK_TYPE"0402LF"
WATTAGE"1/16W"
CDS_LIB"pure_quanta"
CDS_LOCATION"R3938"
$SEC"1"
CDS_SEC"1";
"B"
$PN"2"1;
"A"
$PN"1"35;
%"Q_RES"
"1","(-2700,4000)","0","pure_quanta","I274";
;
PART_NUMBER"CS00002JB13"
PACK_TYPE"0402LF"
MATERIAL"EMPTY"
VALUE"0"
$LOCATION"R4083"
TOLERANCE"5%"
WATTAGE"1/16W"
CDS_LIB"pure_quanta"
CDS_LOCATION"R4083"
$SEC"1"
CDS_SEC"1";
"B"
$PN"2"20;
"A"
$PN"1"77;
%"Q_RES"
"1","(-2700,3900)","0","pure_quanta","I275";
;
PART_NUMBER"CS00002JB13"
VALUE"0"
PACK_TYPE"0402LF"
MATERIAL"EMPTY"
$LOCATION"R4084"
WATTAGE"1/16W"
TOLERANCE"5%"
CDS_LIB"pure_quanta"
CDS_LOCATION"R4084"
$SEC"1"
CDS_SEC"1";
"B"
$PN"2"20;
"A"
$PN"1"71;
%"Q_RES"
"1","(-1425,-600)","0","pure_quanta","I284";
;
PART_NUMBER"CS31002FB08"
MATERIAL"CHIP"
TOLERANCE"1%"
VALUE"10K"
$LOCATION"R4095"
CDS_LIB"pure_quanta"
PACK_TYPE"0402LF"
WATTAGE"1/16W"
CDS_LOCATION"R4095"
$SEC"1"
CDS_SEC"1";
"B"
$PN"2"2;
"A"
$PN"1"47;
%"Q_RES"
"1","(-1425,-650)","0","pure_quanta","I285";
;
PART_NUMBER"CS31002FB08"
MATERIAL"CHIP"
TOLERANCE"1%"
VALUE"10K"
$LOCATION"R4096"
CDS_LIB"pure_quanta"
PACK_TYPE"0402LF"
WATTAGE"1/16W"
CDS_LOCATION"R4096"
$SEC"1"
CDS_SEC"1";
"B"
$PN"2"2;
"A"
$PN"1"46;
%"Q_RES"
"1","(-1425,-700)","0","pure_quanta","I286";
;
PART_NUMBER"CS31002FB08"
VALUE"10K"
MATERIAL"CHIP"
TOLERANCE"1%"
$LOCATION"R4097"
CDS_LIB"pure_quanta"
PACK_TYPE"0402LF"
WATTAGE"1/16W"
CDS_LOCATION"R4097"
$SEC"1"
CDS_SEC"1";
"B"
$PN"2"2;
"A"
$PN"1"45;
%"Q_RES"
"1","(-1425,-750)","0","pure_quanta","I287";
;
PART_NUMBER"CS31002FB08"
VALUE"10K"
TOLERANCE"1%"
MATERIAL"CHIP"
$LOCATION"R4098"
CDS_LIB"pure_quanta"
PACK_TYPE"0402LF"
WATTAGE"1/16W"
CDS_LOCATION"R4098"
$SEC"1"
CDS_SEC"1";
"B"
$PN"2"2;
"A"
$PN"1"127;
%"Q_RES"
"1","(-1425,-800)","0","pure_quanta","I288";
;
PART_NUMBER"CS31002FB08"
TOLERANCE"1%"
VALUE"10K"
MATERIAL"CHIP"
$LOCATION"R4099"
CDS_LIB"pure_quanta"
WATTAGE"1/16W"
PACK_TYPE"0402LF"
CDS_LOCATION"R4099"
$SEC"1"
CDS_SEC"1";
"B"
$PN"2"2;
"A"
$PN"1"128;
%"UNIVERSAL_GND"
"1","(-900,-1050)","0","logical_power","I289";
;
HDL_POWER"GND"
CDS_LIB"logical_power";
"A"2;
%"Q_RES"
"1","(-1425,-950)","0","pure_quanta","I298";
;
PART_NUMBER"CS31002FB08"
TOLERANCE"1%"
VALUE"10K"
MATERIAL"CHIP"
$LOCATION"R4102"
CDS_LIB"pure_quanta"
PACK_TYPE"0402LF"
WATTAGE"1/16W"
CDS_LOCATION"R4102"
$SEC"1"
CDS_SEC"1";
"B"
$PN"2"2;
"A"
$PN"1"130;
%"Q_RES"
"1","(-1425,-900)","0","pure_quanta","I299";
;
PART_NUMBER"CS31002FB08"
TOLERANCE"1%"
VALUE"10K"
MATERIAL"CHIP"
$LOCATION"R4101"
PACK_TYPE"0402LF"
WATTAGE"1/16W"
CDS_LIB"pure_quanta"
CDS_LOCATION"R4101"
$SEC"1"
CDS_SEC"1";
"B"
$PN"2"2;
"A"
$PN"1"140;
%"Q_RES"
"1","(-1425,-850)","0","pure_quanta","I300";
;
PART_NUMBER"CS31002FB08"
MATERIAL"CHIP"
TOLERANCE"1%"
VALUE"10K"
$LOCATION"R4100"
PACK_TYPE"0402LF"
WATTAGE"1/16W"
CDS_LIB"pure_quanta"
CDS_LOCATION"R4100"
$SEC"1"
CDS_SEC"1";
"B"
$PN"2"2;
"A"
$PN"1"129;
%"Q_RES"
"1","(2950,1450)","0","pure_quanta","I305";
;
PART_NUMBER"CS03322FB03"
VALUE"33.2"
MATERIAL"CHIP"
$LOCATION"R4505"
WATTAGE"1/16W"
TOLERANCE"1%"
PACK_TYPE"0402LF"
CDS_LIB"pure_quanta"
CDS_LOCATION"R4505"
$SEC"1"
CDS_SEC"1";
"B"
$PN"2"142;
"A"
$PN"1"60;
%"Q_RES"
"1","(2950,1500)","0","pure_quanta","I308";
;
PART_NUMBER"CS00002JB13"
MATERIAL"CHIP"
VALUE"0"
$LOCATION"R4504"
WATTAGE"1/16W"
TOLERANCE"5%"
PACK_TYPE"0402LF"
CDS_LIB"pure_quanta"
CDS_LOCATION"R4504"
$SEC"1"
CDS_SEC"1";
"B"
$PN"2"143;
"A"
$PN"1"131;
%"Q_RES"
"1","(-2700,3775)","0","pure_quanta","I314";
;
PART_NUMBER"CS04992FB07"
MATERIAL"CHIP"
VALUE"49.9"
LOCATION"R4766"
CDS_LIB"pure_quanta"
WATTAGE"1/16W"
TOLERANCE"1%"
PACK_TYPE"0402LF"
$SEC"1"
CDS_SEC"1";
"B"
$PN"2"20;
"A"
$PN"1"65;
%"Q_RES"
"1","(3475,-1350)","0","pure_quanta","I315";
;
PART_NUMBER"CS31002FB08"
MATERIAL"CHIP"
WATTAGE"1/16W"
PACK_TYPE"0402LF"
VALUE"10K"
TOLERANCE"1%"
$LOCATION"R4768"
CDS_LIB"pure_quanta"
CDS_LOCATION"R4768"
$SEC"1"
CDS_SEC"1";
"B"
$PN"2"1;
"A"
$PN"1"44;
%"EMMITSBURG_REV0P9"
"5","(1325,3200)","0","pure_quanta","I93";
;
PART_NUMBER"AJ0QV2N0T00"
VALUE"GFNOCPU04302300-QV2N-MM#99A1WT"
PART_TYPE"SMLF"
MATERIAL"IC"
$LOCATION"U4"
NEEDS_NO_SIZE"TRUE"
CDS_LMAN_SYM_OUTLINE"-1725,1250,1725,-1250"
CDS_LIB"pure_quanta"
CDS_LOCATION"U4"
$SEC"5"
CDS_SEC"5";
"GPP_D_9_PME_N \B"
$PN"AJ3"112;
"GPP_D_8_CRASHLOG_TRIG_N \B"
$PN"AE3"113;
"GPP_D_7"
$PN"AG1"114;
"GPP_D_6"
$PN"AJ1"117;
"GPP_D_2_HS_SMBALERT_N_DMA_SMBALERT_N \B"
$PN"AD2"125;
"GPP_D_23"
$PN"W1"101;
"GPP_D_22_USB2_OCB_7"
$PN"AA3"98;
"GPP_D_21_GLB_RST_WARN_N \B"
$PN"AA1"102;
"GPP_D_20_CATERR_N \B"
$PN"AG3"126;
"GPP_D_1_HS_SMBDATA_DMA_SMBDATA"
$PN"AE1"118;
"GPP_D_19_MSMI_N \B"
$PN"Y4"105;
"GPP_D_18_MEMTRIP_N \B"
$PN"AF4"104;
"GPP_D_17_THERMTRIP_N \B"
$PN"Y2"103;
"GPP_D_16_ADR_ACK"
$PN"AD4"110;
"GPP_D_15_VRALERT_N \B"
$PN"AC3"109;
"GPP_D_14_ADR_TRIGGER_N \B"
$PN"AH4"108;
"GPP_D_13_ADR_COMPLETE"
$PN"AC1"107;
"GPP_D_12_PCHHOT_N \B"
$PN"AH2"106;
"GPP_D_11_PLTRST_N \B"
$PN"AB4"115;
"GPP_D_10_BM_BUSY_N_SX_EXIT_HOLDOFF_N \B"
$PN"AB2"111;
"GPP_D_0_HS_SMBCLK_DMA_SMBCLK"
$PN"AF2"116;
"GPPC_C_9_ME_SML2CLK"
$PN"AR2"89;
"GPPC_C_8_ME_SML1ALERT_N \B"
$PN"AR4"91;
"GPPC_C_7_ME_SML1DATA"
$PN"AW4"90;
"GPPC_C_6_ME_SML1CLK"
$PN"AP1"94;
"GPPC_C_5_ME_SML0BALERT_N \B"
$PN"AT3"93;
"GPPC_C_4_ME_SML0BCLK"
$PN"BB3"97;
"GPPC_C_3_ME_SML0BDATA"
$PN"AU4"96;
"GPPC_C_2_ME_SML0ALERT_N \B"
$PN"AU2"95;
"GPPC_C_21_MC_SMBALERT_N \B"
$PN"AN2"78;
"GPPC_C_20_MC_SMBDATA"
$PN"AT1"79;
"GPPC_C_1_ME_SML0DATA"
$PN"BA4"100;
"GPPC_C_19_MC_SMBCLK"
$PN"AL1"80;
"GPPC_C_18"
$PN"AL5"81;
"GPPC_C_17_ME_SML4ALERT_N \B"
$PN"AL3"82;
"GPPC_C_16_ME_SML4DATA"
$PN"AV1"87;
"GPPC_C_15_ME_SML4CLK"
$PN"BA2"86;
"GPPC_C_14_ME_SML3ALERT_N \B"
$PN"AW2"83;
"GPPC_C_13_ME_SML3DATA"
$PN"AY1"85;
"GPPC_C_12_ME_SML3CLK"
$PN"AN4"84;
"GPPC_C_11_ME_SML2ALERT_N \B"
$PN"AV3"92;
"GPPC_C_10_ME_SML2DATA"
$PN"AP3"88;
"GPPC_C_0_ME_SML0CLK"
$PN"BC4"99;
"GPPC_B_9_USB2_OCB_4"
$PN"BG26"64;
"GPPC_B_8_USB2_OCB_3"
$PN"BG28"32;
"GPPC_B_7_USB2_OCB_2"
$PN"BG30"63;
"GPPC_B_6_USB2_OCB_1"
$PN"BG32"124;
"GPPC_B_5_USB2_OCB_0"
$PN"BF31"66;
"GPPC_B_4_GSXCLK"
$PN"BE30"33;
"GPPC_B_3_GSXRESET_N \B"
$PN"BD31"62;
"GPPC_B_2_GSXDIN"
$PN"BF33"34;
"GPPC_B_23"
$PN"BD23"12;
"GPPC_B_22"
$PN"BE22"11;
"GPPC_B_21"
$PN"BF23"10;
"GPPC_B_20"
$PN"BE24"9;
"GPPC_B_1_GSXSLOAD"
$PN"BE32"122;
"GPPC_B_19_HS_UART1_CTS_N \B"
$PN"BF25"26;
"GPPC_B_17_HS_UART1_TXD"
$PN"BF27"69;
"GPPC_B_16_HS_UART1_RXD"
$PN"BE26"29;
"GPPC_B_15_HS_UART0_CTS_N \B"
$PN"BD27"27;
"GPPC_B_14_HS_UART0_RTS_N \B"
$PN"BF29"28;
"GPPC_B_13_HS_UART0_TXD"
$PN"BE28"68;
"GPPC_B_12_HS_UART0_RXD"
$PN"BD29"30;
"GPPC_B_11_USB2_OCB_6"
$PN"BG22"67;
"GPPC_B_10_USB2_OCB_5"
$PN"BG24"31;
"GPPC_B_0_GSXDOUT"
$PN"BD33"123;
"GPPC_A_9_ESPI_CLK"
$PN"BD13"21;
"GPPC_A_8_ESPI_RESET_N \B"
$PN"BF17"74;
"GPPC_A_7_ESPI_CS1_N \B"
$PN"BE16"15;
"GPPC_A_6_ESPI_CS0_N \B"
$PN"BE20"23;
"GPPC_A_5_ESPI_IO_3"
$PN"BD19"14;
"GPPC_A_4_ESPI_IO_2"
$PN"BE18"22;
"GPPC_A_3_ESPI_IO_1"
$PN"BF19"24;
"GPPC_A_2_ESPI_IO_0"
$PN"BG12"70;
"GPPC_A_1_ESPI_ALERT1_N \B"
$PN"BD15"25;
"GPPC_A_19_SRCCLKREQ_N_9"
$PN"BG14"119;
"GPPC_A_18_SRCCLKREQ_N_8"
$PN"BF11"120;
"GPPC_A_17_SRCCLKREQ_N_7"
$PN"BF13"121;
"GPPC_A_16_SRCCLKREQ_N_6"
$PN"BD11"18;
"GPPC_A_15_SRCCLKREQ_N_5"
$PN"BE14"17;
"GPPC_A_14_SRCCLKREQ_N_4"
$PN"BE12"16;
"GPPC_A_13_SRCCLKREQ_N_3"
$PN"BF15"19;
"GPPC_A_12_SRCCLKREQ_N_2"
$PN"BG16"76;
"GPPC_A_11_SRCCLKREQ_N_1"
$PN"BG18"20;
"GPPC_A_10_SRCCLKREQ_N_0"
$PN"BD17"75;
"GPPC_A_0_ESPI_ALERT0_N \B"
$PN"BG20"13;
"GPPC_B_18_HS_UART1_RTS_N \B"
$PN"BD25"8;
END.
